# T6G (Grand Teton) — schematic netlist excerpt (pin names and nets, part order shuffled) for the footprints in the layout excerpt that follows; sources: Cadence DE-HDL packaged netlist, KiCad conversion of 04192023_DAF0TMB3IC0_F0TG_MB_C_brd_V02_OCP.brd

C528  Q_CAP  1UF 4V 20% X6S  pkg 0201  page 279 : A = P0V9_CPU0_RT_2D ; B = GND
C2455  Q_CAP  22UF 4V 20% X6S  pkg C0402  page 74 : A = PVDDCR_SOC_P1 ; B = GND
R913  Q_RES  0 5% CHIP  pkg 0201LF  page 353 : A = SMB_RT_CPU1_P3_R_SCL ; B = SMB_RT_CPU1_P3_R2_SCL

(kicad_pcb
	(version 20260206)
	(generator "pcbnew")
	(generator_version "10.0")
	(general
		(thickness 1.6)
		(legacy_teardrops no)
	)
	(paper "A4")
	(title_block
		(title "04192023_DAF0TMB3IC0_F0TG_MB_C_brd_V02_OCP.brd")
		(comment 1 "Grand Teton / footprints 6493-6495 of 8354")
	)
	(layers
		(0 "F.Cu" signal "TOP")
		(4 "In1.Cu" signal "GND")
		(6 "In2.Cu" signal "IN1")
		(8 "In3.Cu" signal "GND1")
		(10 "In4.Cu" signal "IN2")
		(12 "In5.Cu" signal "GND2")
		(14 "In6.Cu" signal "IN3")
		(16 "In7.Cu" signal "GND3")
		(18 "In8.Cu" signal "VCC")
		(20 "In9.Cu" signal "VCC1")
		(22 "In10.Cu" signal "GND4")
		(24 "In11.Cu" signal "IN4")
		(26 "In12.Cu" signal "GND5")
		(28 "In13.Cu" signal "IN5")
		(30 "In14.Cu" signal "GND6")
		(32 "In15.Cu" signal "IN6")
		(34 "In16.Cu" signal "GND7")
		(2 "B.Cu" signal "BOTTOM")
		(9 "F.Adhes" user "F.Adhesive")
		(11 "B.Adhes" user "B.Adhesive")
		(13 "F.Paste" user "Package Geometry/Pastemask Top")
		(15 "B.Paste" user "Package Geometry/Pastemask Bottom")
		(5 "F.SilkS" user "Ref Des/Silkscreen Top")
		(7 "B.SilkS" user "Ref Des/Silkscreen Bottom")
		(1 "F.Mask" user "Board Geometry/Soldermask Top")
		(3 "B.Mask" user "Board Geometry/Soldermask Bottom")
		(17 "Dwgs.User" user "User.Drawings")
		(19 "Cmts.User" user "User.Comments")
		(21 "Eco1.User" user "User.Eco1")
		(23 "Eco2.User" user "User.Eco2")
		(25 "Edge.Cuts" user "Board Geometry/Outline")
		(27 "Margin" user)
		(31 "F.CrtYd" user "Package Geometry/Place Bound Top")
		(29 "B.CrtYd" user "Package Geometry/Place Bound Bottom")
		(35 "F.Fab" user "Ref Des/Assembly Top")
		(33 "B.Fab" user "Ref Des/Assembly Bottom")
	)
	(footprint ""
		(layer "B.Cu")
		(at 104.307386 -253.432564)
		(property "Reference" "C2455"
			(at 0 0 0)
			(layer "B.SilkS")
			(hide yes)
			(effects
				(font
					(size 1.27 1.27)
				)
				(justify mirror)
			)
		)
		(property "Value" ""
			(at 0 0 0)
			(layer "B.Fab")
			(effects
				(font
					(size 1.27 1.27)
				)
				(justify mirror)
			)
		)
		(duplicate_pad_numbers_are_jumpers no)
		(fp_line
			(start -0.7874 -0.4064)
			(end -0.7874 0.4064)
			(stroke
				(width 0.1524)
				(type default)
			)
			(layer "B.SilkS")
		)
		(fp_line
			(start -0.7874 0.4064)
			(end 0.7874 0.4064)
			(stroke
				(width 0.1524)
				(type default)
			)
			(layer "B.SilkS")
		)
		(fp_line
			(start 0.7874 -0.4064)
			(end -0.7874 -0.4064)
			(stroke
				(width 0.1524)
				(type default)
			)
			(layer "B.SilkS")
		)
		(fp_line
			(start 0.7874 0.4064)
			(end 0.7874 -0.4064)
			(stroke
				(width 0.1524)
				(type default)
			)
			(layer "B.SilkS")
		)
		(fp_line
			(start -0.67945 -0.3048)
			(end -0.67945 0.3048)
			(stroke
				(width 0.1)
				(type default)
			)
			(layer "B.Fab")
		)
		(fp_line
			(start -0.67945 0.3048)
			(end -0.120396 0.3048)
			(stroke
				(width 0.1)
				(type default)
			)
			(layer "B.Fab")
		)
		(fp_line
			(start -0.12065 -0.3048)
			(end -0.67945 -0.3048)
			(stroke
				(width 0.1)
				(type default)
			)
			(layer "B.Fab")
		)
		(fp_line
			(start -0.12065 -0.2794)
			(end -0.12065 -0.3048)
			(stroke
				(width 0.1)
				(type default)
			)
			(layer "B.Fab")
		)
		(fp_line
			(start -0.120396 0.2794)
			(end 0.12065 0.2794)
			(stroke
				(width 0.1)
				(type default)
			)
			(layer "B.Fab")
		)
		(fp_line
			(start -0.120396 0.3048)
			(end -0.120396 0.2794)
			(stroke
				(width 0.1)
				(type default)
			)
			(layer "B.Fab")
		)
		(fp_line
			(start 0.12065 -0.305054)
			(end 0.12065 -0.2794)
			(stroke
				(width 0.1)
				(type default)
			)
			(layer "B.Fab")
		)
		(fp_line
			(start 0.12065 -0.2794)
			(end -0.12065 -0.2794)
			(stroke
				(width 0.1)
				(type default)
			)
			(layer "B.Fab")
		)
		(fp_line
			(start 0.12065 0.2794)
			(end 0.12065 0.3048)
			(stroke
				(width 0.1)
				(type default)
			)
			(layer "B.Fab")
		)
		(fp_line
			(start 0.12065 0.3048)
			(end 0.67945 0.3048)
			(stroke
				(width 0.1)
				(type default)
			)
			(layer "B.Fab")
		)
		(fp_line
			(start 0.67945 -0.305054)
			(end 0.12065 -0.305054)
			(stroke
				(width 0.1)
				(type default)
			)
			(layer "B.Fab")
		)
		(fp_line
			(start 0.67945 0.3048)
			(end 0.67945 -0.305054)
			(stroke
				(width 0.1)
				(type default)
			)
			(layer "B.Fab")
		)
		(pad "1" smd circle
			(at 0.40005 0 180)
			(size 0 0)
			(layers "B.Cu" "B.Mask" "B.Paste")
			(net "PVDDCR_SOC_P1")
		)
		(pad "2" smd circle
			(at -0.40005 0 180)
			(size 0 0)
			(layers "B.Cu" "B.Mask" "B.Paste")
			(net "GND")
		)
	)
	(footprint ""
		(layer "B.Cu")
		(at 214.122 -339.598)
		(property "Reference" "R913"
			(at 0 0 0)
			(layer "B.SilkS")
			(hide yes)
			(effects
				(font
					(size 1.27 1.27)
				)
				(justify mirror)
			)
		)
		(property "Value" ""
			(at 0 0 0)
			(layer "B.Fab")
			(effects
				(font
					(size 1.27 1.27)
				)
				(justify mirror)
			)
		)
		(duplicate_pad_numbers_are_jumpers no)
		(fp_line
			(start -0.32512 -0.175006)
			(end -0.32512 0.175006)
			(stroke
				(width 0.1)
				(type default)
			)
			(layer "B.Fab")
		)
		(fp_line
			(start -0.32512 0.175006)
			(end 0.32512 0.175006)
			(stroke
				(width 0.1)
				(type default)
			)
			(layer "B.Fab")
		)
		(fp_line
			(start 0.32512 -0.175006)
			(end -0.32512 -0.175006)
			(stroke
				(width 0.1)
				(type default)
			)
			(layer "B.Fab")
		)
		(fp_line
			(start 0.32512 0.175006)
			(end 0.32512 -0.175006)
			(stroke
				(width 0.1)
				(type default)
			)
			(layer "B.Fab")
		)
		(pad "1" smd rect
			(at 0.2667 0 180)
			(size 0.3048 0.381)
			(layers "B.Cu" "B.Mask" "B.Paste")
			(net "SMB_RT_CPU1_P3_R_SCL")
		)
		(pad "2" smd rect
			(at -0.2667 0)
			(size 0.3048 0.381)
			(layers "B.Cu" "B.Mask" "B.Paste")
			(net "SMB_RT_CPU1_P3_R2_SCL")
		)
	)
	(footprint ""
		(layer "B.Cu")
		(at 315.391038 -399.291302 90)
		(property "Reference" "C528"
			(at 0 0 90)
			(layer "B.SilkS")
			(hide yes)
			(effects
				(font
					(size 1.27 1.27)
				)
				(justify mirror)
			)
		)
		(property "Value" ""
			(at 0 0 90)
			(layer "B.Fab")
			(effects
				(font
					(size 1.27 1.27)
				)
				(justify mirror)
			)
		)
		(duplicate_pad_numbers_are_jumpers no)
		(fp_line
			(start 0.299974 -0.150114)
			(end -0.299974 -0.150114)
			(stroke
				(width 0.1)
				(type default)
			)
			(layer "B.Fab")
		)
		(fp_line
			(start -0.299974 -0.150114)
			(end -0.299974 0.150114)
			(stroke
				(width 0.1)
				(type default)
			)
			(layer "B.Fab")
		)
		(fp_line
			(start 0.299974 0.150114)
			(end 0.299974 -0.150114)
			(stroke
				(width 0.1)
				(type default)
			)
			(layer "B.Fab")
		)
		(fp_line
			(start -0.299974 0.150114)
			(end 0.299974 0.150114)
			(stroke
				(width 0.1)
				(type default)
			)
			(layer "B.Fab")
		)
		(pad "1" smd rect
			(at 0.2667 0 270)
			(size 0.3048 0.381)
			(layers "B.Cu" "B.Mask" "B.Paste")
			(net "P0V9_CPU0_RT_2D")
		)
		(pad "2" smd rect
			(at -0.2667 0 270)
			(size 0.3048 0.381)
			(layers "B.Cu" "B.Mask" "B.Paste")
			(net "GND")
		)
	)
)
